(kicad_pcb
	(version 20260206)
	(generator "pcbnew")
	(generator_version "10.0")
	(general
		(thickness 1.6)
		(legacy_teardrops no)
	)
	(paper "A4")
	(title_block
		(title "Bryce Canyon_IOM_M2_16342-2_OCP.brd")
		(comment 1 "Bryce Canyon / footprint 69 of 1146 (U2), pads 1-113 of 456")
	)
	(layers
		(0 "F.Cu" signal "TOP")
		(4 "In1.Cu" signal "L2GND")
		(6 "In2.Cu" signal "L3")
		(8 "In3.Cu" signal "L4VCC")
		(10 "In4.Cu" signal "L5VCC")
		(12 "In5.Cu" signal "L6")
		(14 "In6.Cu" signal "L7GND")
		(2 "B.Cu" signal "BOTTOM")
		(9 "F.Adhes" user "F.Adhesive")
		(11 "B.Adhes" user "B.Adhesive")
		(13 "F.Paste" user "Package Geometry/Pastemask Top")
		(15 "B.Paste" user "Package Geometry/Pastemask Bottom")
		(5 "F.SilkS" user "Ref Des/Silkscreen Top")
		(7 "B.SilkS" user "Ref Des/Silkscreen Bottom")
		(1 "F.Mask" user "Board Geometry/Soldermask Top")
		(3 "B.Mask" user "Board Geometry/Soldermask Bottom")
		(17 "Dwgs.User" user "User.Drawings")
		(19 "Cmts.User" user "User.Comments")
		(21 "Eco1.User" user "User.Eco1")
		(23 "Eco2.User" user "User.Eco2")
		(25 "Edge.Cuts" user "Board Geometry/Outline")
		(27 "Margin" user)
		(31 "F.CrtYd" user "Package Geometry/Place Bound Top")
		(29 "B.CrtYd" user "Package Geometry/Place Bound Bottom")
		(35 "F.Fab" user "Ref Des/Assembly Top")
		(33 "B.Fab" user "Ref Des/Assembly Bottom")
	)
	(footprint ""
		(layer "F.Cu")
		(at 47.69993 -144.999964 -90)
		(property "Reference" "U2"
			(at 0 0 270)
			(layer "F.SilkS")
			(hide yes)
			(effects
				(font
					(size 1.27 1.27)
				)
			)
		)
		(property "Value" "AST2500A2-GP-GP-U"
			(at -17.0307 -8.584692 270)
			(unlocked yes)
			(layer "F.Fab")
			(hide yes)
			(effects
				(font
					(size 1.016 1.016)
					(thickness 0.1524)
				)
			)
		)
		(property "Device Type" "BGA456D19H58"
			(at -17.0307 -10.108692 270)
			(unlocked yes)
			(layer "F.Fab")
			(hide yes)
			(effects
				(font
					(size 1.016 1.016)
					(thickness 0.1524)
				)
			)
		)
		(duplicate_pad_numbers_are_jumpers no)
		(pad "A1" smd circle
			(at -8.400034 -8.400034 270)
			(size 0.4064 0.4064)
			(layers "F.Cu" "F.Mask" "F.Paste")
			(net "GND")
		)
		(pad "A2" smd circle
			(at -7.599934 -8.400034 270)
			(size 0.4064 0.4064)
			(layers "F.Cu" "F.Mask" "F.Paste")
			(net "MAC2_TXD0")
		)
		(pad "A3" smd circle
			(at -6.800088 -8.400034 270)
			(size 0.4064 0.4064)
			(layers "F.Cu" "F.Mask" "F.Paste")
			(net "NCSI_RXD0")
		)
		(pad "A4" smd circle
			(at -5.999988 -8.400034 270)
			(size 0.3556 0.3556)
			(layers "F.Cu" "F.Mask" "F.Paste")
			(net "BMC_RGMII_A4_D3")
		)
		(pad "A5" smd circle
			(at -5.199888 -8.400034 270)
			(size 0.3556 0.3556)
			(layers "F.Cu" "F.Mask" "F.Paste")
			(net "NCSI_TXD1_R")
		)
		(pad "A6" smd circle
			(at -4.400042 -8.400034 270)
			(size 0.3556 0.3556)
			(layers "F.Cu" "F.Mask" "F.Paste")
			(net "USB_P3_DN")
		)
		(pad "A7" smd circle
			(at -3.599942 -8.400034 270)
			(size 0.3556 0.3556)
			(layers "F.Cu" "F.Mask" "F.Paste")
			(net "USB_P2_DP")
		)
		(pad "A8" smd circle
			(at -2.800096 -8.400034 270)
			(size 0.3556 0.3556)
			(layers "F.Cu" "F.Mask" "F.Paste")
			(net "USB_P2_DN")
		)
		(pad "A9" smd circle
			(at -1.999996 -8.400034 270)
			(size 0.3556 0.3556)
			(layers "F.Cu" "F.Mask" "F.Paste")
			(net "BMC_SMB4_CLK")
		)
		(pad "A10" smd circle
			(at -1.199896 -8.400034 270)
			(size 0.3556 0.3556)
			(layers "F.Cu" "F.Mask" "F.Paste")
			(net "BMC_SMB3_DAT")
		)
		(pad "A11" smd circle
			(at -0.40005 -8.400034 270)
			(size 0.3556 0.3556)
			(layers "F.Cu" "F.Mask" "F.Paste")
			(net "BMC_SMB3_CLK")
		)
		(pad "A12" smd circle
			(at 0.40005 -8.400034 270)
			(size 0.3556 0.3556)
			(layers "F.Cu" "F.Mask" "F.Paste")
			(net "BMC_SMB10_DAT")
		)
		(pad "A13" smd circle
			(at 1.199896 -8.400034 270)
			(size 0.3556 0.3556)
			(layers "F.Cu" "F.Mask" "F.Paste")
			(net "BMC_SMB9_DAT")
		)
		(pad "A14" smd circle
			(at 1.999996 -8.400034 270)
			(size 0.3556 0.3556)
			(layers "F.Cu" "F.Mask" "F.Paste")
			(net "TP_BMC_GPIOI6")
		)
		(pad "A15" smd circle
			(at 2.800096 -8.400034 270)
			(size 0.3556 0.3556)
			(layers "F.Cu" "F.Mask" "F.Paste")
			(net "TP_BMC_GPIOI7")
		)
		(pad "A16" smd circle
			(at 3.599942 -8.400034 270)
			(size 0.3556 0.3556)
			(layers "F.Cu" "F.Mask" "F.Paste")
			(net "LED_POSTCODE_6")
		)
		(pad "A17" smd circle
			(at 4.400042 -8.400034 270)
			(size 0.3556 0.3556)
			(layers "F.Cu" "F.Mask" "F.Paste")
			(net "LED_POSTCODE_4")
		)
		(pad "A18" smd circle
			(at 5.199888 -8.400034 270)
			(size 0.3556 0.3556)
			(layers "F.Cu" "F.Mask" "F.Paste")
			(net "LED_POSTCODE_0")
		)
		(pad "A19" smd circle
			(at 5.999988 -8.400034 270)
			(size 0.3556 0.3556)
			(layers "F.Cu" "F.Mask" "F.Paste")
			(net "SLOTID_0")
		)
		(pad "A20" smd circle
			(at 6.800088 -8.400034 270)
			(size 0.4064 0.4064)
			(layers "F.Cu" "F.Mask" "F.Paste")
			(net "TP_BMC_EXT2_LED_B")
		)
		(pad "A21" smd circle
			(at 7.599934 -8.400034 270)
			(size 0.4064 0.4064)
			(layers "F.Cu" "F.Mask" "F.Paste")
			(net "SCC_PWR_EN_R")
		)
		(pad "A22" smd circle
			(at 8.400034 -8.400034 270)
			(size 0.4064 0.4064)
			(layers "F.Cu" "F.Mask" "F.Paste")
			(net "GND")
		)
		(pad "AA1" smd circle
			(at -8.400034 7.599934 270)
			(size 0.4064 0.4064)
			(layers "F.Cu" "F.Mask" "F.Paste")
			(net "Net_563")
		)
		(pad "AA2" smd circle
			(at -7.599934 7.599934 270)
			(size 0.4064 0.4064)
			(layers "F.Cu" "F.Mask" "F.Paste")
			(net "Net_562")
		)
		(pad "AA3" smd circle
			(at -6.800088 7.599934 270)
			(size 0.4064 0.4064)
			(layers "F.Cu" "F.Mask" "F.Paste")
			(net "TP_BMC_GPION5")
		)
		(pad "AA4" smd circle
			(at -5.999988 7.599934 270)
			(size 0.3556 0.3556)
			(layers "F.Cu" "F.Mask" "F.Paste")
			(net "COMP_POWER_FAIL_R_N")
		)
		(pad "AA5" smd circle
			(at -5.199888 7.599934 270)
			(size 0.3556 0.3556)
			(layers "F.Cu" "F.Mask" "F.Paste")
			(net "THROTTLE_N")
		)
		(pad "AA6" smd circle
			(at -4.400042 7.599934 270)
			(size 0.3556 0.3556)
			(layers "F.Cu" "F.Mask" "F.Paste")
			(net "MEMDQ_12")
		)
		(pad "AA7" smd circle
			(at -3.599942 7.599934 270)
			(size 0.3556 0.3556)
			(layers "F.Cu" "F.Mask" "F.Paste")
			(net "GND")
		)
		(pad "AA8" smd circle
			(at -2.800096 7.599934 270)
			(size 0.3556 0.3556)
			(layers "F.Cu" "F.Mask" "F.Paste")
			(net "MEMDQ_8")
		)
		(pad "AA9" smd circle
			(at -1.999996 7.599934 270)
			(size 0.3556 0.3556)
			(layers "F.Cu" "F.Mask" "F.Paste")
			(net "GND")
		)
		(pad "AA10" smd circle
			(at -1.199896 7.599934 270)
			(size 0.3556 0.3556)
			(layers "F.Cu" "F.Mask" "F.Paste")
			(net "MEMDQ_3")
		)
		(pad "AA11" smd circle
			(at -0.40005 7.599934 270)
			(size 0.3556 0.3556)
			(layers "F.Cu" "F.Mask" "F.Paste")
			(net "GND")
		)
		(pad "AA12" smd circle
			(at 0.40005 7.599934 270)
			(size 0.3556 0.3556)
			(layers "F.Cu" "F.Mask" "F.Paste")
			(net "MEMCSN")
		)
		(pad "AA13" smd circle
			(at 1.199896 7.599934 270)
			(size 0.3556 0.3556)
			(layers "F.Cu" "F.Mask" "F.Paste")
			(net "GND")
		)
		(pad "AA14" smd circle
			(at 1.999996 7.599934 270)
			(size 0.3556 0.3556)
			(layers "F.Cu" "F.Mask" "F.Paste")
			(net "MEMA_11")
		)
		(pad "AA15" smd circle
			(at 2.800096 7.599934 270)
			(size 0.3556 0.3556)
			(layers "F.Cu" "F.Mask" "F.Paste")
			(net "GND")
		)
		(pad "AA16" smd circle
			(at 3.599942 7.599934 270)
			(size 0.3556 0.3556)
			(layers "F.Cu" "F.Mask" "F.Paste")
			(net "MEMA_7")
		)
		(pad "AA17" smd circle
			(at 4.400042 7.599934 270)
			(size 0.3556 0.3556)
			(layers "F.Cu" "F.Mask" "F.Paste")
			(net "P1V15_STBY")
		)
		(pad "AA18" smd circle
			(at 5.199888 7.599934 270)
			(size 0.3556 0.3556)
			(layers "F.Cu" "F.Mask" "F.Paste")
			(net "BMC_SPI_CLK")
		)
		(pad "AA19" smd circle
			(at 5.999988 7.599934 270)
			(size 0.3556 0.3556)
			(layers "F.Cu" "F.Mask" "F.Paste")
			(net "FLA_CS_1")
		)
		(pad "AA20" smd circle
			(at 6.800088 7.599934 270)
			(size 0.4064 0.4064)
			(layers "F.Cu" "F.Mask" "F.Paste")
			(net "BMC_GPIOS7")
		)
		(pad "AA21" smd circle
			(at 7.599934 7.599934 270)
			(size 0.4064 0.4064)
			(layers "F.Cu" "F.Mask" "F.Paste")
			(net "PLTRST_R")
		)
		(pad "AA22" smd circle
			(at 8.400034 7.599934 270)
			(size 0.4064 0.4064)
			(layers "F.Cu" "F.Mask" "F.Paste")
			(net "TPM_PRSNT_N_R")
		)
		(pad "AB1" smd circle
			(at -8.400034 8.400034 270)
			(size 0.4064 0.4064)
			(layers "F.Cu" "F.Mask" "F.Paste")
			(net "GND")
		)
		(pad "AB2" smd circle
			(at -7.599934 8.400034 270)
			(size 0.4064 0.4064)
			(layers "F.Cu" "F.Mask" "F.Paste")
			(net "Net_561")
		)
		(pad "AB3" smd circle
			(at -6.800088 8.400034 270)
			(size 0.4064 0.4064)
			(layers "F.Cu" "F.Mask" "F.Paste")
			(net "SCC_A_HB_IN_R")
		)
		(pad "AB4" smd circle
			(at -5.999988 8.400034 270)
			(size 0.3556 0.3556)
			(layers "F.Cu" "F.Mask" "F.Paste")
			(net "ENCL_FAULT_LED_R")
		)
		(pad "AB5" smd circle
			(at -5.199888 8.400034 270)
			(size 0.3556 0.3556)
			(layers "F.Cu" "F.Mask" "F.Paste")
			(net "DEBUG_GPIO_BMC_R_1")
		)
		(pad "AB6" smd circle
			(at -4.400042 8.400034 270)
			(size 0.3556 0.3556)
			(layers "F.Cu" "F.Mask" "F.Paste")
			(net "MEMDQS_N1")
		)
		(pad "AB7" smd circle
			(at -3.599942 8.400034 270)
			(size 0.3556 0.3556)
			(layers "F.Cu" "F.Mask" "F.Paste")
			(net "MEMDQS_P1")
		)
		(pad "AB8" smd circle
			(at -2.800096 8.400034 270)
			(size 0.3556 0.3556)
			(layers "F.Cu" "F.Mask" "F.Paste")
			(net "MEMDM_1")
		)
		(pad "AB9" smd circle
			(at -1.999996 8.400034 270)
			(size 0.3556 0.3556)
			(layers "F.Cu" "F.Mask" "F.Paste")
			(net "MEMDQS_P0")
		)
		(pad "AB10" smd circle
			(at -1.199896 8.400034 270)
			(size 0.3556 0.3556)
			(layers "F.Cu" "F.Mask" "F.Paste")
			(net "MEMDQS_N0")
		)
		(pad "AB11" smd circle
			(at -0.40005 8.400034 270)
			(size 0.3556 0.3556)
			(layers "F.Cu" "F.Mask" "F.Paste")
			(net "MEMCK_P")
		)
		(pad "AB12" smd circle
			(at 0.40005 8.400034 270)
			(size 0.3556 0.3556)
			(layers "F.Cu" "F.Mask" "F.Paste")
			(net "MEMCK_N")
		)
		(pad "AB13" smd circle
			(at 1.199896 8.400034 270)
			(size 0.3556 0.3556)
			(layers "F.Cu" "F.Mask" "F.Paste")
			(net "MEMCASN")
		)
		(pad "AB14" smd circle
			(at 1.999996 8.400034 270)
			(size 0.3556 0.3556)
			(layers "F.Cu" "F.Mask" "F.Paste")
			(net "MEMA_1")
		)
		(pad "AB15" smd circle
			(at 2.800096 8.400034 270)
			(size 0.3556 0.3556)
			(layers "F.Cu" "F.Mask" "F.Paste")
			(net "MEMA_13")
		)
		(pad "AB16" smd circle
			(at 3.599942 8.400034 270)
			(size 0.3556 0.3556)
			(layers "F.Cu" "F.Mask" "F.Paste")
			(net "MEMA_6")
		)
		(pad "AB17" smd circle
			(at 4.400042 8.400034 270)
			(size 0.3556 0.3556)
			(layers "F.Cu" "F.Mask" "F.Paste")
			(net "DDR4_RST_N")
		)
		(pad "AB18" smd circle
			(at 5.199888 8.400034 270)
			(size 0.3556 0.3556)
			(layers "F.Cu" "F.Mask" "F.Paste")
			(net "PECI")
		)
		(pad "AB19" smd circle
			(at 5.999988 8.400034 270)
			(size 0.3556 0.3556)
			(layers "F.Cu" "F.Mask" "F.Paste")
			(net "FLA_CS_0")
		)
		(pad "AB20" smd circle
			(at 6.800088 8.400034 270)
			(size 0.4064 0.4064)
			(layers "F.Cu" "F.Mask" "F.Paste")
			(net "BMC_ML_PWR_YELLOW_LED")
		)
		(pad "AB21" smd circle
			(at 7.599934 8.400034 270)
			(size 0.4064 0.4064)
			(layers "F.Cu" "F.Mask" "F.Paste")
			(net "BMC_ML_PWR_BLUE_LED")
		)
		(pad "AB22" smd circle
			(at 8.400034 8.400034 270)
			(size 0.4064 0.4064)
			(layers "F.Cu" "F.Mask" "F.Paste")
			(net "GND")
		)
		(pad "B1" smd circle
			(at -8.400034 -7.599934 270)
			(size 0.4064 0.4064)
			(layers "F.Cu" "F.Mask" "F.Paste")
			(net "MAC2_TXCTL")
		)
		(pad "B2" smd circle
			(at -7.599934 -7.599934 270)
			(size 0.4064 0.4064)
			(layers "F.Cu" "F.Mask" "F.Paste")
			(net "TP_BMC_GPIOT6")
		)
		(pad "B3" smd circle
			(at -6.800088 -7.599934 270)
			(size 0.4064 0.4064)
			(layers "F.Cu" "F.Mask" "F.Paste")
			(net "MAC2_TXD1")
		)
		(pad "B4" smd circle
			(at -5.999988 -7.599934 270)
			(size 0.3556 0.3556)
			(layers "F.Cu" "F.Mask" "F.Paste")
			(net "CLK_50M_BMC_NCSI")
		)
		(pad "B5" smd circle
			(at -5.199888 -7.599934 270)
			(size 0.3556 0.3556)
			(layers "F.Cu" "F.Mask" "F.Paste")
			(net "TP_BMC_GPIOT0")
		)
		(pad "B6" smd circle
			(at -4.400042 -7.599934 270)
			(size 0.3556 0.3556)
			(layers "F.Cu" "F.Mask" "F.Paste")
			(net "USB_P3_DP")
		)
		(pad "B7" smd circle
			(at -3.599942 -7.599934 270)
			(size 0.3556 0.3556)
			(layers "F.Cu" "F.Mask" "F.Paste")
			(net "PD_USB2BVRES")
		)
		(pad "B8" smd circle
			(at -2.800096 -7.599934 270)
			(size 0.3556 0.3556)
			(layers "F.Cu" "F.Mask" "F.Paste")
			(net "PD_USB2AVRES")
		)
		(pad "B9" smd circle
			(at -1.999996 -7.599934 270)
			(size 0.3556 0.3556)
			(layers "F.Cu" "F.Mask" "F.Paste")
			(net "BMC_SMB4_DAT")
		)
		(pad "B10" smd circle
			(at -1.199896 -7.599934 270)
			(size 0.3556 0.3556)
			(layers "F.Cu" "F.Mask" "F.Paste")
			(net "DB_PRSNT_BMC_N")
		)
		(pad "B11" smd circle
			(at -0.40005 -7.599934 270)
			(size 0.3556 0.3556)
			(layers "F.Cu" "F.Mask" "F.Paste")
			(net "BMC_SMB13_DAT")
		)
		(pad "B12" smd circle
			(at 0.40005 -7.599934 270)
			(size 0.3556 0.3556)
			(layers "F.Cu" "F.Mask" "F.Paste")
			(net "BMC_SMB11_CLK")
		)
		(pad "B13" smd circle
			(at 1.199896 -7.599934 270)
			(size 0.3556 0.3556)
			(layers "F.Cu" "F.Mask" "F.Paste")
			(net "TP_BMC_GPIOA7")
		)
		(pad "B14" smd circle
			(at 1.999996 -7.599934 270)
			(size 0.3556 0.3556)
			(layers "F.Cu" "F.Mask" "F.Paste")
			(net "TP_BMC_GPIOA0")
		)
		(pad "B15" smd circle
			(at 2.800096 -7.599934 270)
			(size 0.3556 0.3556)
			(layers "F.Cu" "F.Mask" "F.Paste")
			(net "TP_BMC_GPIOI4")
		)
		(pad "B16" smd circle
			(at 3.599942 -7.599934 270)
			(size 0.3556 0.3556)
			(layers "F.Cu" "F.Mask" "F.Paste")
			(net "TP_BMC_GPIOI2")
		)
		(pad "B17" smd circle
			(at 4.400042 -7.599934 270)
			(size 0.3556 0.3556)
			(layers "F.Cu" "F.Mask" "F.Paste")
			(net "LED_POSTCODE_5")
		)
		(pad "B18" smd circle
			(at 5.199888 -7.599934 270)
			(size 0.3556 0.3556)
			(layers "F.Cu" "F.Mask" "F.Paste")
			(net "LED_POSTCODE_1")
		)
		(pad "B19" smd circle
			(at 5.999988 -7.599934 270)
			(size 0.3556 0.3556)
			(layers "F.Cu" "F.Mask" "F.Paste")
			(net "TP_BMC_EXT2_LED_G")
		)
		(pad "B20" smd circle
			(at 6.800088 -7.599934 270)
			(size 0.4064 0.4064)
			(layers "F.Cu" "F.Mask" "F.Paste")
			(net "M2_1_PRESENT_N")
		)
		(pad "B21" smd circle
			(at 7.599934 -7.599934 270)
			(size 0.4064 0.4064)
			(layers "F.Cu" "F.Mask" "F.Paste")
			(net "EXP_SPARE_1_R")
		)
		(pad "B22" smd circle
			(at 8.400034 -7.599934 270)
			(size 0.4064 0.4064)
			(layers "F.Cu" "F.Mask" "F.Paste")
			(net "EXP_SPARE_0_R")
		)
		(pad "C1" smd circle
			(at -8.400034 -6.800088 270)
			(size 0.4064 0.4064)
			(layers "F.Cu" "F.Mask" "F.Paste")
			(net "BMC_RGMII_A4_D3")
		)
		(pad "C2" smd circle
			(at -7.599934 -6.800088 270)
			(size 0.4064 0.4064)
			(layers "F.Cu" "F.Mask" "F.Paste")
			(net "BMC_RGMII_C2_C3_D1_D2_E6")
		)
		(pad "C3" smd circle
			(at -6.800088 -6.800088 270)
			(size 0.4064 0.4064)
			(layers "F.Cu" "F.Mask" "F.Paste")
			(net "BMC_RGMII_C2_C3_D1_D2_E6")
		)
		(pad "C4" smd circle
			(at -5.999988 -6.800088 270)
			(size 0.3556 0.3556)
			(layers "F.Cu" "F.Mask" "F.Paste")
			(net "NCSI_RX_ER")
		)
		(pad "C5" smd circle
			(at -5.199888 -6.800088 270)
			(size 0.3556 0.3556)
			(layers "F.Cu" "F.Mask" "F.Paste")
			(net "NCSI_RCSDV")
		)
		(pad "C6" smd circle
			(at -4.400042 -6.800088 270)
			(size 0.3556 0.3556)
			(layers "F.Cu" "F.Mask" "F.Paste")
			(net "GND")
		)
		(pad "C7" smd circle
			(at -3.599942 -6.800088 270)
			(size 0.3556 0.3556)
			(layers "F.Cu" "F.Mask" "F.Paste")
			(net "P3V3_STBY")
		)
		(pad "C8" smd circle
			(at -2.800096 -6.800088 270)
			(size 0.3556 0.3556)
			(layers "F.Cu" "F.Mask" "F.Paste")
			(net "JTAG_BMC_TMS")
		)
		(pad "C9" smd circle
			(at -1.999996 -6.800088 270)
			(size 0.3556 0.3556)
			(layers "F.Cu" "F.Mask" "F.Paste")
			(net "BMC0_JTAG_RTCK")
		)
		(pad "C10" smd circle
			(at -1.199896 -6.800088 270)
			(size 0.3556 0.3556)
			(layers "F.Cu" "F.Mask" "F.Paste")
			(net "JTAG_BMC_TCK")
		)
		(pad "C11" smd circle
			(at -0.40005 -6.800088 270)
			(size 0.3556 0.3556)
			(layers "F.Cu" "F.Mask" "F.Paste")
			(net "BMC_SMB13_CLK")
		)
		(pad "C12" smd circle
			(at 0.40005 -6.800088 270)
			(size 0.3556 0.3556)
			(layers "F.Cu" "F.Mask" "F.Paste")
			(net "BMC_SMB10_CLK")
		)
		(pad "C13" smd circle
			(at 1.199896 -6.800088 270)
			(size 0.3556 0.3556)
			(layers "F.Cu" "F.Mask" "F.Paste")
			(net "TP_BMC_GPIOA6")
		)
		(pad "C14" smd circle
			(at 1.999996 -6.800088 270)
			(size 0.3556 0.3556)
			(layers "F.Cu" "F.Mask" "F.Paste")
			(net "BMC_SMB9_CLK")
		)
		(pad "C15" smd circle
			(at 2.800096 -6.800088 270)
			(size 0.3556 0.3556)
			(layers "F.Cu" "F.Mask" "F.Paste")
			(net "TP_BMC_GPIOI5")
		)
		(pad "C16" smd circle
			(at 3.599942 -6.800088 270)
			(size 0.3556 0.3556)
			(layers "F.Cu" "F.Mask" "F.Paste")
			(net "TP_BMC_GPIOI3")
		)
		(pad "C17" smd circle
			(at 4.400042 -6.800088 270)
			(size 0.3556 0.3556)
			(layers "F.Cu" "F.Mask" "F.Paste")
			(net "LED_POSTCODE_3")
		)
		(pad "C18" smd circle
			(at 5.199888 -6.800088 270)
			(size 0.3556 0.3556)
			(layers "F.Cu" "F.Mask" "F.Paste")
			(net "TP_BMC_GPIOI0")
		)
		(pad "C19" smd circle
			(at 5.999988 -6.800088 270)
			(size 0.3556 0.3556)
			(layers "F.Cu" "F.Mask" "F.Paste")
			(net "COMP_SPARE_0_R")
		)
		(pad "C20" smd circle
			(at 6.800088 -6.800088 270)
			(size 0.4064 0.4064)
			(layers "F.Cu" "F.Mask" "F.Paste")
			(net "M2_2_PRESENT_N")
		)
		(pad "C21" smd circle
			(at 7.599934 -6.800088 270)
			(size 0.4064 0.4064)
			(layers "F.Cu" "F.Mask" "F.Paste")
			(net "Net_548")
		)
		(pad "C22" smd circle
			(at 8.400034 -6.800088 270)
			(size 0.4064 0.4064)
			(layers "F.Cu" "F.Mask" "F.Paste")
			(net "LPC_CPU_CLKOUT0")
		)
		(pad "D1" smd circle
			(at -8.400034 -5.999988 270)
			(size 0.3556 0.3556)
			(layers "F.Cu" "F.Mask" "F.Paste")
			(net "BMC_RGMII_C2_C3_D1_D2_E6")
		)
		(pad "D2" smd circle
			(at -7.599934 -5.999988 270)
			(size 0.3556 0.3556)
			(layers "F.Cu" "F.Mask" "F.Paste")
			(net "BMC_RGMII_C2_C3_D1_D2_E6")
		)
		(pad "D3" smd circle
			(at -6.800088 -5.999988 270)
			(size 0.3556 0.3556)
			(layers "F.Cu" "F.Mask" "F.Paste")
			(net "BMC_RGMII_A4_D3")
		)
	)
)
